(kicad_pcb
	(version 20260206)
	(generator "pcbnew")
	(generator_version "10.0")
	(general
		(thickness 1.6)
		(legacy_teardrops no)
	)
	(paper "A4")
	(title_block
		(title "04192023_DAF0TMB3IC0_F0TG_MB_C_brd_V02_OCP.brd")
		(comment 1 "Grand Teton / footprints 3493-3497 of 8354")
	)
	(layers
		(0 "F.Cu" signal "TOP")
		(4 "In1.Cu" signal "GND")
		(6 "In2.Cu" signal "IN1")
		(8 "In3.Cu" signal "GND1")
		(10 "In4.Cu" signal "IN2")
		(12 "In5.Cu" signal "GND2")
		(14 "In6.Cu" signal "IN3")
		(16 "In7.Cu" signal "GND3")
		(18 "In8.Cu" signal "VCC")
		(20 "In9.Cu" signal "VCC1")
		(22 "In10.Cu" signal "GND4")
		(24 "In11.Cu" signal "IN4")
		(26 "In12.Cu" signal "GND5")
		(28 "In13.Cu" signal "IN5")
		(30 "In14.Cu" signal "GND6")
		(32 "In15.Cu" signal "IN6")
		(34 "In16.Cu" signal "GND7")
		(2 "B.Cu" signal "BOTTOM")
		(9 "F.Adhes" user "F.Adhesive")
		(11 "B.Adhes" user "B.Adhesive")
		(13 "F.Paste" user "Package Geometry/Pastemask Top")
		(15 "B.Paste" user "Package Geometry/Pastemask Bottom")
		(5 "F.SilkS" user "Ref Des/Silkscreen Top")
		(7 "B.SilkS" user "Ref Des/Silkscreen Bottom")
		(1 "F.Mask" user "Board Geometry/Soldermask Top")
		(3 "B.Mask" user "Board Geometry/Soldermask Bottom")
		(17 "Dwgs.User" user "User.Drawings")
		(19 "Cmts.User" user "User.Comments")
		(21 "Eco1.User" user "User.Eco1")
		(23 "Eco2.User" user "User.Eco2")
		(25 "Edge.Cuts" user "Board Geometry/Outline")
		(27 "Margin" user)
		(31 "F.CrtYd" user "Package Geometry/Place Bound Top")
		(29 "B.CrtYd" user "Package Geometry/Place Bound Bottom")
		(35 "F.Fab" user "Ref Des/Assembly Top")
		(33 "B.Fab" user "Ref Des/Assembly Bottom")
	)
	(footprint ""
		(layer "F.Cu")
		(at 83.054444 -152.093676 180)
		(property "Reference" "PL26"
			(at 0 0 180)
			(layer "F.SilkS")
			(hide yes)
			(effects
				(font
					(size 1.27 1.27)
				)
			)
		)
		(property "Value" ""
			(at 0 0 180)
			(layer "F.Fab")
			(effects
				(font
					(size 1.27 1.27)
				)
			)
		)
		(duplicate_pad_numbers_are_jumpers no)
		(fp_line
			(start 1.27 0.5842)
			(end 1.27 -0.5842)
			(stroke
				(width 0.1524)
				(type default)
			)
			(layer "F.SilkS")
		)
		(fp_line
			(start 1.27 0.5842)
			(end -1.27 0.5842)
			(stroke
				(width 0.1524)
				(type default)
			)
			(layer "F.SilkS")
		)
		(fp_line
			(start -1.27 0.5842)
			(end -1.27 -0.5842)
			(stroke
				(width 0.1524)
				(type default)
			)
			(layer "F.SilkS")
		)
		(fp_line
			(start -1.27 -0.5588)
			(end -1.27 -0.5842)
			(stroke
				(width 0.1524)
				(type default)
			)
			(layer "F.SilkS")
		)
		(fp_line
			(start -1.27 -0.5842)
			(end 1.27 -0.5842)
			(stroke
				(width 0.1524)
				(type default)
			)
			(layer "F.SilkS")
		)
		(fp_line
			(start 1.1938 0.4064)
			(end 0.9144 0.4064)
			(stroke
				(width 0.1)
				(type default)
			)
			(layer "F.Fab")
		)
		(fp_line
			(start 1.1938 -0.406654)
			(end 1.1938 0.4064)
			(stroke
				(width 0.1)
				(type default)
			)
			(layer "F.Fab")
		)
		(fp_line
			(start 0.9144 0.508)
			(end -0.9144 0.508)
			(stroke
				(width 0.1)
				(type default)
			)
			(layer "F.Fab")
		)
		(fp_line
			(start 0.9144 0.4064)
			(end 0.9144 0.508)
			(stroke
				(width 0.1)
				(type default)
			)
			(layer "F.Fab")
		)
		(fp_line
			(start 0.9144 -0.406654)
			(end 1.1938 -0.406654)
			(stroke
				(width 0.1)
				(type default)
			)
			(layer "F.Fab")
		)
		(fp_line
			(start 0.9144 -0.508)
			(end 0.9144 -0.406654)
			(stroke
				(width 0.1)
				(type default)
			)
			(layer "F.Fab")
		)
		(fp_line
			(start -0.9144 0.508)
			(end -0.9144 0.406654)
			(stroke
				(width 0.1)
				(type default)
			)
			(layer "F.Fab")
		)
		(fp_line
			(start -0.9144 0.406654)
			(end -1.194308 0.406654)
			(stroke
				(width 0.1)
				(type default)
			)
			(layer "F.Fab")
		)
		(fp_line
			(start -0.9144 -0.406654)
			(end -0.9144 -0.508)
			(stroke
				(width 0.1)
				(type default)
			)
			(layer "F.Fab")
		)
		(fp_line
			(start -0.9144 -0.508)
			(end 0.9144 -0.508)
			(stroke
				(width 0.1)
				(type default)
			)
			(layer "F.Fab")
		)
		(fp_line
			(start -1.194308 0.406654)
			(end -1.194308 -0.406654)
			(stroke
				(width 0.1)
				(type default)
			)
			(layer "F.Fab")
		)
		(fp_line
			(start -1.194308 -0.406654)
			(end -0.9144 -0.406654)
			(stroke
				(width 0.1)
				(type default)
			)
			(layer "F.Fab")
		)
		(pad "1" smd rect
			(at -0.7366 0 90)
			(size 0.7112 0.8128)
			(layers "F.Cu" "F.Mask" "F.Paste")
			(net "P12V_AUX")
		)
		(pad "2" smd rect
			(at 0.7366 0 90)
			(size 0.7112 0.8128)
			(layers "F.Cu" "F.Mask" "F.Paste")
			(net "SW_P12V_AUX_PVDD18_S5_P1_FLT")
		)
	)
	(footprint ""
		(layer "F.Cu")
		(at 47.462694 -17.623536 90)
		(property "Reference" "C701"
			(at 0 0 90)
			(layer "F.SilkS")
			(hide yes)
			(effects
				(font
					(size 1.27 1.27)
				)
			)
		)
		(property "Value" ""
			(at 0 0 90)
			(layer "F.Fab")
			(effects
				(font
					(size 1.27 1.27)
				)
			)
		)
		(duplicate_pad_numbers_are_jumpers no)
		(fp_line
			(start 0.299974 -0.150114)
			(end 0.299974 0.150114)
			(stroke
				(width 0.1)
				(type default)
			)
			(layer "F.Fab")
		)
		(fp_line
			(start -0.299974 -0.150114)
			(end 0.299974 -0.150114)
			(stroke
				(width 0.1)
				(type default)
			)
			(layer "F.Fab")
		)
		(fp_line
			(start 0.299974 0.150114)
			(end -0.299974 0.150114)
			(stroke
				(width 0.1)
				(type default)
			)
			(layer "F.Fab")
		)
		(fp_line
			(start -0.299974 0.150114)
			(end -0.299974 -0.150114)
			(stroke
				(width 0.1)
				(type default)
			)
			(layer "F.Fab")
		)
		(pad "1" smd rect
			(at -0.2667 0 90)
			(size 0.3048 0.381)
			(layers "F.Cu" "F.Mask" "F.Paste")
			(net "P5E_CPU1_G1_TX_C_DP<4>")
		)
		(pad "2" smd rect
			(at 0.2667 0 90)
			(size 0.3048 0.381)
			(layers "F.Cu" "F.Mask" "F.Paste")
			(net "P5E_CPU1_G1_TX_DP<4>")
		)
	)
	(footprint ""
		(layer "F.Cu")
		(at 290.399724 -403.086062)
		(property "Reference" "U15"
			(at -0.024384 -3.107436 0)
			(unlocked yes)
			(layer "F.SilkS")
			(effects
				(font
					(size 0.7874 0.5842)
					(thickness 0.1524)
				)
				(justify left)
			)
		)
		(property "Value" ""
			(at 0 0 0)
			(layer "F.Fab")
			(effects
				(font
					(size 1.27 1.27)
				)
			)
		)
		(duplicate_pad_numbers_are_jumpers no)
		(fp_line
			(start -1.8288 -2.500122)
			(end -1.8288 2.500122)
			(stroke
				(width 0.1524)
				(type default)
			)
			(layer "F.SilkS")
		)
		(fp_line
			(start -1.8288 2.500122)
			(end 1.8288 2.500122)
			(stroke
				(width 0.1524)
				(type default)
			)
			(layer "F.SilkS")
		)
		(fp_line
			(start -1.077722 -2.500122)
			(end -1.8288 -2.500122)
			(stroke
				(width 0.1524)
				(type default)
			)
			(layer "F.SilkS")
		)
		(fp_line
			(start 0 -1.4224)
			(end -1.077722 -2.500122)
			(stroke
				(width 0.1524)
				(type default)
			)
			(layer "F.SilkS")
		)
		(fp_line
			(start 1.077722 -2.500122)
			(end 0 -1.4224)
			(stroke
				(width 0.1524)
				(type default)
			)
			(layer "F.SilkS")
		)
		(fp_line
			(start 1.8288 -2.500122)
			(end 1.077722 -2.500122)
			(stroke
				(width 0.1524)
				(type default)
			)
			(layer "F.SilkS")
		)
		(fp_line
			(start 1.8288 2.500122)
			(end 1.8288 -2.500122)
			(stroke
				(width 0.1524)
				(type default)
			)
			(layer "F.SilkS")
		)
		(fp_poly
			(pts
				(xy -1.170432 -3.243326) (xy -2.085594 -3.684778) (xy -2.069592 -2.54889)
			)
			(stroke
				(width 0)
				(type default)
			)
			(fill yes)
			(layer "F.SilkS")
		)
		(fp_line
			(start -1.999996 -2.500122)
			(end -1.999996 2.500122)
			(stroke
				(width 0.1)
				(type default)
			)
			(layer "F.Fab")
		)
		(fp_line
			(start -1.999996 2.500122)
			(end 1.999996 2.500122)
			(stroke
				(width 0.1)
				(type default)
			)
			(layer "F.Fab")
		)
		(fp_line
			(start 1.999996 -2.500122)
			(end -1.999996 -2.500122)
			(stroke
				(width 0.1)
				(type default)
			)
			(layer "F.Fab")
		)
		(fp_line
			(start 1.999996 2.500122)
			(end 1.999996 -2.500122)
			(stroke
				(width 0.1)
				(type default)
			)
			(layer "F.Fab")
		)
		(fp_poly
			(pts
				(xy -4.5085 -2.413) (xy -4.5085 -1.397) (xy -3.4925 -1.905)
			)
			(stroke
				(width 0)
				(type default)
			)
			(fill yes)
			(layer "F.Fab")
		)
		(pad "1" smd rect
			(at -2.599944 -1.905 270)
			(size 0.889 1.27)
			(layers "F.Cu" "F.Mask" "F.Paste")
			(net "Net_10843")
		)
		(pad "2" smd rect
			(at -2.599944 -0.635 270)
			(size 0.889 1.27)
			(layers "F.Cu" "F.Mask" "F.Paste")
			(net "Net_10842")
		)
		(pad "3" smd rect
			(at -2.599944 0.635 270)
			(size 0.889 1.27)
			(layers "F.Cu" "F.Mask" "F.Paste")
			(net "U15_E2")
		)
		(pad "4" smd rect
			(at -2.599944 1.905 270)
			(size 0.889 1.27)
			(layers "F.Cu" "F.Mask" "F.Paste")
			(net "GND")
		)
		(pad "5" smd rect
			(at 2.599944 1.905 270)
			(size 0.889 1.27)
			(layers "F.Cu" "F.Mask" "F.Paste")
			(net "SMB_RT_CPU0_P1_ROM_SDA")
		)
		(pad "6" smd rect
			(at 2.599944 0.635 270)
			(size 0.889 1.27)
			(layers "F.Cu" "F.Mask" "F.Paste")
			(net "SMB_RT_CPU0_P1_ROM_SCL")
		)
		(pad "7" smd rect
			(at 2.599944 -0.635 270)
			(size 0.889 1.27)
			(layers "F.Cu" "F.Mask" "F.Paste")
			(net "GND")
		)
		(pad "8" smd rect
			(at 2.599944 -1.905 270)
			(size 0.889 1.27)
			(layers "F.Cu" "F.Mask" "F.Paste")
			(net "P1V8_CPU0_RT_1D")
		)
	)
	(footprint ""
		(layer "F.Cu")
		(at 252.83287 -42.055542 -90)
		(property "Reference" "PU294"
			(at -0.455168 -1.924812 0)
			(unlocked yes)
			(layer "F.SilkS")
			(effects
				(font
					(size 0.7874 0.5842)
					(thickness 0.1524)
				)
				(justify left)
			)
		)
		(property "Value" ""
			(at 0 0 270)
			(layer "F.Fab")
			(effects
				(font
					(size 1.27 1.27)
				)
			)
		)
		(duplicate_pad_numbers_are_jumpers no)
		(fp_line
			(start -1.774952 1.039876)
			(end 1.774952 1.039876)
			(stroke
				(width 0.1524)
				(type default)
			)
			(layer "F.SilkS")
		)
		(fp_line
			(start 1.774952 1.039876)
			(end 1.774952 -1.039876)
			(stroke
				(width 0.1524)
				(type default)
			)
			(layer "F.SilkS")
		)
		(fp_line
			(start -1.774952 -1.039876)
			(end -1.774952 1.039876)
			(stroke
				(width 0.1524)
				(type default)
			)
			(layer "F.SilkS")
		)
		(fp_line
			(start 1.774952 -1.039876)
			(end -1.774952 -1.039876)
			(stroke
				(width 0.1524)
				(type default)
			)
			(layer "F.SilkS")
		)
		(fp_poly
			(pts
				(xy -0.999998 -1.801876) (xy -0.999998 -1.039876) (xy -1.769872 -1.039876) (xy -1.769872 -0.249936)
				(xy -2.531872 -0.249936) (xy -2.531872 -1.801876)
			)
			(stroke
				(width 0)
				(type default)
			)
			(fill yes)
			(layer "F.SilkS")
		)
		(fp_line
			(start -1.769872 1.039876)
			(end 1.769872 1.039876)
			(stroke
				(width 0.1)
				(type default)
			)
			(layer "F.Fab")
		)
		(fp_line
			(start 1.769872 1.039876)
			(end 1.769872 -1.039876)
			(stroke
				(width 0.1)
				(type default)
			)
			(layer "F.Fab")
		)
		(fp_line
			(start -1.769872 -1.039876)
			(end -1.769872 1.039876)
			(stroke
				(width 0.1)
				(type default)
			)
			(layer "F.Fab")
		)
		(fp_line
			(start 1.769872 -1.039876)
			(end -1.769872 -1.039876)
			(stroke
				(width 0.1)
				(type default)
			)
			(layer "F.Fab")
		)
		(fp_poly
			(pts
				(xy -1.769872 -1.039876) (xy -0.999998 -1.039876) (xy -0.999998 -1.801876) (xy -2.531872 -1.801876)
				(xy -2.531872 -0.249936) (xy -1.769872 -0.249936)
			)
			(stroke
				(width 0)
				(type default)
			)
			(fill yes)
			(layer "F.Fab")
		)
		(pad "A1" smd circle
			(at -1.500124 -0.750062 270)
			(size 0.2286 0.2286)
			(layers "F.Cu" "F.Mask" "F.Paste")
			(net "P12V_E1S_SENSE_0")
		)
		(pad "A2" smd circle
			(at -0.999998 -0.750062 270)
			(size 0.2286 0.2286)
			(layers "F.Cu" "F.Mask" "F.Paste")
			(net "P12V_E1S_VCC_0")
		)
		(pad "A3" smd circle
			(at -0.499872 -0.750062 270)
			(size 0.2286 0.2286)
			(layers "F.Cu" "F.Mask" "F.Paste")
			(net "P12V_AUX")
		)
		(pad "A4" smd circle
			(at 0 -0.750062 270)
			(size 0.2286 0.2286)
			(layers "F.Cu" "F.Mask" "F.Paste")
			(net "P12V_E1S_0")
		)
		(pad "A5" smd circle
			(at 0.499872 -0.750062 270)
			(size 0.2286 0.2286)
			(layers "F.Cu" "F.Mask" "F.Paste")
			(net "P12V_AUX")
		)
		(pad "A6" smd circle
			(at 0.999998 -0.750062 270)
			(size 0.2286 0.2286)
			(layers "F.Cu" "F.Mask" "F.Paste")
			(net "P12V_E1S_GATE_0")
		)
		(pad "A7" smd circle
			(at 1.500124 -0.750062 270)
			(size 0.2286 0.2286)
			(layers "F.Cu" "F.Mask" "F.Paste")
			(net "GND")
		)
		(pad "B1" smd circle
			(at -1.500124 -0.249936 270)
			(size 0.2286 0.2286)
			(layers "F.Cu" "F.Mask" "F.Paste")
			(net "P12V_E1S_CB_0")
		)
		(pad "B2" smd circle
			(at -0.999998 -0.249936 270)
			(size 0.2286 0.2286)
			(layers "F.Cu" "F.Mask" "F.Paste")
			(net "GND")
		)
		(pad "B3" smd circle
			(at -0.499872 -0.249936 270)
			(size 0.2286 0.2286)
			(layers "F.Cu" "F.Mask" "F.Paste")
			(net "P12V_AUX")
		)
		(pad "B4" smd circle
			(at 0 -0.249936 270)
			(size 0.2286 0.2286)
			(layers "F.Cu" "F.Mask" "F.Paste")
			(net "P12V_E1S_0")
		)
		(pad "B5" smd circle
			(at 0.499872 -0.249936 270)
			(size 0.2286 0.2286)
			(layers "F.Cu" "F.Mask" "F.Paste")
			(net "P12V_AUX")
		)
		(pad "B6" smd circle
			(at 0.999998 -0.249936 270)
			(size 0.2286 0.2286)
			(layers "F.Cu" "F.Mask" "F.Paste")
			(net "P12V_E1S_0")
		)
		(pad "B7" smd circle
			(at 1.500124 -0.249936 270)
			(size 0.2286 0.2286)
			(layers "F.Cu" "F.Mask" "F.Paste")
			(net "GND")
		)
		(pad "C1" smd circle
			(at -1.500124 0.249936 270)
			(size 0.2286 0.2286)
			(layers "F.Cu" "F.Mask" "F.Paste")
			(net "GND")
		)
		(pad "C2" smd circle
			(at -0.999998 0.249936 270)
			(size 0.2286 0.2286)
			(layers "F.Cu" "F.Mask" "F.Paste")
			(net "GND")
		)
		(pad "C3" smd circle
			(at -0.499872 0.249936 270)
			(size 0.2286 0.2286)
			(layers "F.Cu" "F.Mask" "F.Paste")
			(net "P12V_AUX")
		)
		(pad "C4" smd circle
			(at 0 0.249936 270)
			(size 0.2286 0.2286)
			(layers "F.Cu" "F.Mask" "F.Paste")
			(net "P12V_E1S_0")
		)
		(pad "C5" smd circle
			(at 0.499872 0.249936 270)
			(size 0.2286 0.2286)
			(layers "F.Cu" "F.Mask" "F.Paste")
			(net "P12V_AUX")
		)
		(pad "C6" smd circle
			(at 0.999998 0.249936 270)
			(size 0.2286 0.2286)
			(layers "F.Cu" "F.Mask" "F.Paste")
			(net "P12V_E1S_0")
		)
		(pad "C7" smd circle
			(at 1.500124 0.249936 270)
			(size 0.2286 0.2286)
			(layers "F.Cu" "F.Mask" "F.Paste")
			(net "P12V_E1S_FAULT_0")
		)
		(pad "D1" smd circle
			(at -1.500124 0.750062 270)
			(size 0.2286 0.2286)
			(layers "F.Cu" "F.Mask" "F.Paste")
			(net "P12V_E1S_REG_0")
		)
		(pad "D2" smd circle
			(at -0.999998 0.750062 270)
			(size 0.2286 0.2286)
			(layers "F.Cu" "F.Mask" "F.Paste")
			(net "P12V_E1S_UV_0")
		)
		(pad "D3" smd circle
			(at -0.499872 0.750062 270)
			(size 0.2286 0.2286)
			(layers "F.Cu" "F.Mask" "F.Paste")
			(net "P12V_E1S_OV_0")
		)
		(pad "D4" smd circle
			(at 0 0.750062 270)
			(size 0.2286 0.2286)
			(layers "F.Cu" "F.Mask" "F.Paste")
			(net "P12V_E1S_0")
		)
		(pad "D5" smd circle
			(at 0.499872 0.750062 270)
			(size 0.2286 0.2286)
			(layers "F.Cu" "F.Mask" "F.Paste")
			(net "P12V_AUX")
		)
		(pad "D6" smd circle
			(at 0.999998 0.750062 270)
			(size 0.2286 0.2286)
			(layers "F.Cu" "F.Mask" "F.Paste")
			(net "P12V_E1S_0")
		)
		(pad "D7" smd circle
			(at 1.500124 0.750062 270)
			(size 0.2286 0.2286)
			(layers "F.Cu" "F.Mask" "F.Paste")
			(net "P12V_E1S_PWRGD_0")
		)
	)
	(footprint ""
		(layer "F.Cu")
		(at 111.952024 -65.092072)
		(property "Reference" "U6003"
			(at -2.1082 -3.165348 0)
			(unlocked yes)
			(layer "F.SilkS")
			(effects
				(font
					(size 0.7874 0.5842)
					(thickness 0.1524)
				)
				(justify left)
			)
		)
		(property "Value" ""
			(at 0 0 0)
			(layer "F.Fab")
			(effects
				(font
					(size 1.27 1.27)
				)
			)
		)
		(duplicate_pad_numbers_are_jumpers no)
		(fp_line
			(start -1.8288 -2.500122)
			(end -1.8288 2.500122)
			(stroke
				(width 0.1524)
				(type default)
			)
			(layer "F.SilkS")
		)
		(fp_line
			(start -1.8288 2.500122)
			(end 1.8288 2.500122)
			(stroke
				(width 0.1524)
				(type default)
			)
			(layer "F.SilkS")
		)
		(fp_line
			(start -1.077722 -2.500122)
			(end -1.8288 -2.500122)
			(stroke
				(width 0.1524)
				(type default)
			)
			(layer "F.SilkS")
		)
		(fp_line
			(start 0 -1.4224)
			(end -1.077722 -2.500122)
			(stroke
				(width 0.1524)
				(type default)
			)
			(layer "F.SilkS")
		)
		(fp_line
			(start 1.077722 -2.500122)
			(end 0 -1.4224)
			(stroke
				(width 0.1524)
				(type default)
			)
			(layer "F.SilkS")
		)
		(fp_line
			(start 1.8288 -2.500122)
			(end 1.077722 -2.500122)
			(stroke
				(width 0.1524)
				(type default)
			)
			(layer "F.SilkS")
		)
		(fp_line
			(start 1.8288 2.500122)
			(end 1.8288 -2.500122)
			(stroke
				(width 0.1524)
				(type default)
			)
			(layer "F.SilkS")
		)
		(fp_poly
			(pts
				(xy -2.313178 -3.971798) (xy -3.329178 -3.971798) (xy -2.821178 -2.955798)
			)
			(stroke
				(width 0)
				(type default)
			)
			(fill yes)
			(layer "F.SilkS")
		)
		(fp_line
			(start -1.999996 -2.500122)
			(end -1.999996 2.500122)
			(stroke
				(width 0.1)
				(type default)
			)
			(layer "F.Fab")
		)
		(fp_line
			(start -1.999996 2.500122)
			(end 1.999996 2.500122)
			(stroke
				(width 0.1)
				(type default)
			)
			(layer "F.Fab")
		)
		(fp_line
			(start 1.999996 -2.500122)
			(end -1.999996 -2.500122)
			(stroke
				(width 0.1)
				(type default)
			)
			(layer "F.Fab")
		)
		(fp_line
			(start 1.999996 2.500122)
			(end 1.999996 -2.500122)
			(stroke
				(width 0.1)
				(type default)
			)
			(layer "F.Fab")
		)
		(fp_poly
			(pts
				(xy -4.5085 -2.413) (xy -4.5085 -1.397) (xy -3.4925 -1.905)
			)
			(stroke
				(width 0)
				(type default)
			)
			(fill yes)
			(layer "F.Fab")
		)
		(pad "1" smd rect
			(at -2.599944 -1.905 270)
			(size 0.889 1.27)
			(layers "F.Cu" "F.Mask" "F.Paste")
			(net "USB_CPU0_ADD_A0")
		)
		(pad "2" smd rect
			(at -2.599944 -0.635 270)
			(size 0.889 1.27)
			(layers "F.Cu" "F.Mask" "F.Paste")
			(net "USB_CPU0_ADD_A1")
		)
		(pad "3" smd rect
			(at -2.599944 0.635 270)
			(size 0.889 1.27)
			(layers "F.Cu" "F.Mask" "F.Paste")
			(net "USB_CPU0_ADD_A2")
		)
		(pad "4" smd rect
			(at -2.599944 1.905 270)
			(size 0.889 1.27)
			(layers "F.Cu" "F.Mask" "F.Paste")
			(net "GND")
		)
		(pad "5" smd rect
			(at 2.599944 1.905 270)
			(size 0.889 1.27)
			(layers "F.Cu" "F.Mask" "F.Paste")
			(net "SMB_USB_CPU0_HUB1_SDA_R2")
		)
		(pad "6" smd rect
			(at 2.599944 0.635 270)
			(size 0.889 1.27)
			(layers "F.Cu" "F.Mask" "F.Paste")
			(net "SMB_USB_CPU0_HUB1_SCL_R2")
		)
		(pad "7" smd rect
			(at 2.599944 -0.635 270)
			(size 0.889 1.27)
			(layers "F.Cu" "F.Mask" "F.Paste")
			(net "PD_USB_CPU0_WP")
		)
		(pad "8" smd rect
			(at 2.599944 -1.905 270)
			(size 0.889 1.27)
			(layers "F.Cu" "F.Mask" "F.Paste")
			(net "P3V3_AUX")
		)
	)
)
